G04*
G04 #@! TF.GenerationSoftware,Altium Limited,Altium Designer,23.0.1 (38)*
G04*
G04 Layer_Color=32768*
%FSLAX25Y25*%
%MOIN*%
G70*
G04*
G04 #@! TF.SameCoordinates,C48E81DB-6E20-4E2D-80E6-7C5AFAA1A21F*
G04*
G04*
G04 #@! TF.FilePolarity,Positive*
G04*
G01*
G75*
%ADD16C,0.00394*%
%ADD20C,0.00600*%
%ADD258C,0.00197*%
%ADD259C,0.00400*%
G36*
X586522Y-280045D02*
Y-282997D01*
X584179D01*
Y-283296D01*
X563065D01*
Y-282997D01*
X560722D01*
Y-280045D01*
X560405D01*
Y-264050D01*
X560722D01*
Y-261097D01*
X563065D01*
Y-260798D01*
X584179D01*
Y-261097D01*
X586522D01*
Y-264050D01*
X586839D01*
Y-280045D01*
X586522D01*
D02*
G37*
G36*
X597696Y-221438D02*
Y-224390D01*
X595353D01*
Y-224689D01*
X574240D01*
Y-224390D01*
X571896D01*
Y-221438D01*
X571579D01*
Y-205443D01*
X571896D01*
Y-202490D01*
X574240D01*
Y-202192D01*
X595353D01*
Y-202490D01*
X597696D01*
Y-205443D01*
X598014D01*
Y-221438D01*
X597696D01*
D02*
G37*
D16*
X82677Y-127953D02*
Y-124016D01*
X80709Y-125984D02*
X84646D01*
X66634Y-113779D02*
X68799D01*
X67716Y-114862D02*
Y-112697D01*
X66634Y-110236D02*
X68799D01*
X67716Y-111319D02*
Y-109153D01*
X66634Y-117717D02*
X68799D01*
X67716Y-118799D02*
Y-116634D01*
X661516Y-81102D02*
X663681D01*
X662598Y-82185D02*
Y-80020D01*
X674508Y-78347D02*
X676673D01*
X675591Y-79429D02*
Y-77264D01*
X550394Y-271949D02*
Y-269783D01*
X549311Y-270866D02*
X551476D01*
X608957Y-81890D02*
X611122D01*
X610039Y-82972D02*
Y-80807D01*
X605217Y-101181D02*
X607382D01*
X606299Y-102264D02*
Y-100098D01*
X582382Y-80709D02*
X584547D01*
X583465Y-81791D02*
Y-79626D01*
X574705Y-106299D02*
X576870D01*
X575787Y-107382D02*
Y-105217D01*
X235039Y-116437D02*
Y-114272D01*
X233957Y-115354D02*
X236122D01*
X237894Y-122441D02*
X240059D01*
X238976Y-123524D02*
Y-121358D01*
X256791Y-104724D02*
X258957D01*
X257874Y-105807D02*
Y-103642D01*
X259842Y-121555D02*
Y-119390D01*
X258760Y-120472D02*
X260925D01*
X166535Y-111319D02*
Y-107579D01*
X164665Y-109449D02*
X168405D01*
X267323Y-118898D02*
X270866D01*
X269094Y-120669D02*
Y-117126D01*
X237008Y-110236D02*
Y-106299D01*
X235039Y-108268D02*
X238976D01*
X671260Y-82185D02*
Y-80020D01*
X670177Y-81102D02*
X672342D01*
X678445Y-67716D02*
X680610D01*
X679528Y-68799D02*
Y-66634D01*
X626476Y-86614D02*
X628642D01*
X627559Y-87697D02*
Y-85532D01*
X605610Y-89764D02*
X607776D01*
X606693Y-90847D02*
Y-88681D01*
X626870Y-99606D02*
X629035D01*
X627953Y-100689D02*
Y-98524D01*
X605610Y-95276D02*
X607776D01*
X606693Y-96358D02*
Y-94193D01*
X594095Y-86122D02*
Y-83957D01*
X593012Y-85039D02*
X595177D01*
X437106Y-111024D02*
X439272D01*
X438189Y-112106D02*
Y-109941D01*
X407087Y-110630D02*
X409252D01*
X408169Y-111713D02*
Y-109547D01*
X572933Y-88189D02*
X575098D01*
X574016Y-89272D02*
Y-87106D01*
X593405Y-98032D02*
X595571D01*
X594488Y-99114D02*
Y-96949D01*
X572539Y-100394D02*
X574705D01*
X573622Y-101476D02*
Y-99311D01*
X243012Y-114173D02*
X245177D01*
X244094Y-115256D02*
Y-113091D01*
X243012Y-130709D02*
X245177D01*
X244094Y-131791D02*
Y-129626D01*
X254429Y-115354D02*
X256594D01*
X255512Y-116437D02*
Y-114272D01*
X252854Y-130709D02*
X255020D01*
X253937Y-131791D02*
Y-129626D01*
X667717Y-82185D02*
Y-80020D01*
X666634Y-81102D02*
X668799D01*
X679232Y-41339D02*
X681398D01*
X680315Y-42421D02*
Y-40256D01*
X696457Y-47539D02*
Y-45374D01*
X695374Y-46457D02*
X697539D01*
X549016Y-265945D02*
X551378D01*
X550197Y-267126D02*
Y-264764D01*
X640945Y-207874D02*
Y-203937D01*
X638976Y-205906D02*
X642913D01*
X594488Y-231102D02*
Y-228740D01*
X593307Y-229921D02*
X595669D01*
X605610Y-232283D02*
X607776D01*
X606693Y-233366D02*
Y-231201D01*
X666634Y-243701D02*
X668799D01*
X667717Y-244783D02*
Y-242618D01*
X673622Y-243209D02*
Y-241043D01*
X672539Y-242126D02*
X674705D01*
X599213Y-231004D02*
Y-228839D01*
X598130Y-229921D02*
X600295D01*
X642520Y-225590D02*
X644882D01*
X643701Y-226772D02*
Y-224409D01*
X566142Y-200689D02*
Y-198524D01*
X565059Y-199606D02*
X567224D01*
X550886Y-200394D02*
X553051D01*
X551968Y-201476D02*
Y-199311D01*
X554724Y-214469D02*
Y-212303D01*
X553642Y-213386D02*
X555807D01*
X561909Y-205512D02*
X564075D01*
X562992Y-206594D02*
Y-204429D01*
X561909Y-209055D02*
X564075D01*
X562992Y-210138D02*
Y-207972D01*
X551968Y-110138D02*
Y-107973D01*
X550886Y-109055D02*
X553051D01*
X564173Y-110531D02*
Y-108366D01*
X563091Y-109449D02*
X565256D01*
X549311Y-274803D02*
X551476D01*
X550394Y-275886D02*
Y-273721D01*
X582382Y-289764D02*
X584547D01*
X583465Y-290846D02*
Y-288681D01*
X637402Y-269291D02*
X641339D01*
X639370Y-271260D02*
Y-267323D01*
X594095Y-285039D02*
Y-282677D01*
X592913Y-283858D02*
X595276D01*
X549016Y-285039D02*
X551181D01*
X550098Y-286122D02*
Y-283957D01*
X582382Y-285433D02*
X584547D01*
X583465Y-286516D02*
Y-284350D01*
X552953Y-260728D02*
Y-258563D01*
X551870Y-259646D02*
X554035D01*
X664567Y-284252D02*
Y-281890D01*
X663386Y-283071D02*
X665748D01*
X682283Y-303051D02*
Y-300886D01*
X681201Y-301969D02*
X683366D01*
X682283Y-307382D02*
Y-305217D01*
X681201Y-306299D02*
X683366D01*
X576772Y-147244D02*
Y-143307D01*
X574803Y-145276D02*
X578740D01*
X534252Y-142520D02*
Y-140157D01*
X533071Y-141339D02*
X535433D01*
X498032Y-142520D02*
Y-140157D01*
X496850Y-141339D02*
X499213D01*
X498032Y-138583D02*
Y-136221D01*
X496850Y-137402D02*
X499213D01*
X504724Y-112500D02*
Y-110335D01*
X503642Y-111417D02*
X505807D01*
X508661Y-112500D02*
Y-110335D01*
X507579Y-111417D02*
X509744D01*
X473622Y-123130D02*
Y-120965D01*
X472539Y-122047D02*
X474705D01*
X490650Y-109055D02*
X492815D01*
X491732Y-110138D02*
Y-107973D01*
X470965Y-116929D02*
X473130D01*
X472047Y-118012D02*
Y-115847D01*
X483957Y-109055D02*
X486122D01*
X485039Y-110138D02*
Y-107973D01*
X503248Y-119685D02*
X505413D01*
X504331Y-120768D02*
Y-118602D01*
X473327Y-134646D02*
X475492D01*
X474409Y-135728D02*
Y-133563D01*
X501575Y-125591D02*
X503937D01*
X502756Y-126772D02*
Y-124409D01*
X503937Y-134646D02*
Y-132283D01*
X502756Y-133465D02*
X505118D01*
X478346Y-110138D02*
Y-107972D01*
X477264Y-109055D02*
X479429D01*
X53937Y-39764D02*
X57874D01*
X55905Y-41732D02*
Y-37795D01*
X109449Y-40551D02*
X113386D01*
X111417Y-42520D02*
Y-38583D01*
X668110Y-49213D02*
Y-45276D01*
X666142Y-47244D02*
X670079D01*
X605512Y-46850D02*
Y-42913D01*
X603543Y-44882D02*
X607480D01*
X424803Y-184941D02*
Y-182776D01*
X423721Y-183858D02*
X425886D01*
X139075Y-129528D02*
X141240D01*
X140157Y-130610D02*
Y-128445D01*
X365300Y-114567D02*
Y-110630D01*
X363332Y-112598D02*
X367268D01*
X363332Y-136221D02*
X367268D01*
X365300Y-138189D02*
Y-134252D01*
X568110Y-122441D02*
Y-118504D01*
X566142Y-120472D02*
X570079D01*
X593307Y-167717D02*
X597244D01*
X595276Y-169685D02*
Y-165748D01*
X363332Y-124803D02*
X367268D01*
X365300Y-126772D02*
Y-122835D01*
X47244Y-3839D02*
Y-98D01*
X45374Y-1969D02*
X49114D01*
X40354Y-3839D02*
Y-98D01*
X38484Y-1969D02*
X42224D01*
X33465Y-3839D02*
Y-98D01*
X31594Y-1969D02*
X35335D01*
X26575Y-3839D02*
Y-98D01*
X24705Y-1969D02*
X28445D01*
X101378Y-125984D02*
X105315D01*
X103347Y-127953D02*
Y-124016D01*
X-22736Y-192323D02*
Y-173622D01*
X-14469D01*
Y-192323D02*
Y-173622D01*
X-22736Y-192323D02*
X-14469D01*
X-22736Y-245079D02*
Y-226378D01*
X-14469D01*
Y-245079D02*
Y-226378D01*
X-22736Y-245079D02*
X-14469D01*
X-22736Y-298622D02*
Y-279921D01*
X-14469D01*
Y-298622D02*
Y-279921D01*
X-22736Y-298622D02*
X-14469D01*
X-22736Y-351378D02*
Y-332677D01*
X-14469D01*
Y-351378D02*
Y-332677D01*
X-22736Y-351378D02*
X-14469D01*
X79724Y-137697D02*
Y-133957D01*
X77854Y-135827D02*
X81595D01*
X44291Y-264764D02*
Y-260827D01*
X42323Y-262795D02*
X46260D01*
X44291Y-159449D02*
Y-155512D01*
X42323Y-157480D02*
X46260D01*
X72933Y-332677D02*
X76673D01*
X74803Y-334547D02*
Y-330807D01*
X80807Y-332677D02*
X84547D01*
X82677Y-334547D02*
Y-330807D01*
X44291Y-318898D02*
Y-314961D01*
X42323Y-316929D02*
X46260D01*
X44291Y-212598D02*
Y-208661D01*
X42323Y-210630D02*
X46260D01*
X55118Y-316929D02*
X58661D01*
X56890Y-318701D02*
Y-315158D01*
X56299Y-210630D02*
X59842D01*
X58071Y-212402D02*
Y-208858D01*
X56299Y-262795D02*
X59842D01*
X58071Y-264567D02*
Y-261024D01*
X73917Y-224409D02*
X77658D01*
X75787Y-226279D02*
Y-222539D01*
X80807Y-224410D02*
X84547D01*
X82677Y-226279D02*
Y-222539D01*
X81791Y-278543D02*
X85532D01*
X83661Y-280413D02*
Y-276673D01*
X73917Y-278543D02*
X77658D01*
X75787Y-280413D02*
Y-276673D01*
X72933Y-172244D02*
X76673D01*
X74803Y-174114D02*
Y-170374D01*
X80807Y-172244D02*
X84547D01*
X82677Y-174114D02*
Y-170374D01*
X-22736Y-118504D02*
Y-99803D01*
X-14469D01*
Y-118504D02*
Y-99803D01*
X-22736Y-118504D02*
X-14469D01*
X-22736Y-75197D02*
Y-56496D01*
X-14469D01*
Y-75197D02*
Y-56496D01*
X-22736Y-75197D02*
X-14469D01*
X456791Y-137647D02*
X460532D01*
X458661Y-139517D02*
Y-135777D01*
X668898Y-18110D02*
Y-14173D01*
X666929Y-16142D02*
X670866D01*
X612766Y-15985D02*
Y-12049D01*
X610798Y-14017D02*
X614735D01*
X65945Y-332677D02*
X69882D01*
X67913Y-334646D02*
Y-330709D01*
X27756Y-187795D02*
X41142D01*
X27596Y-171555D02*
X41094D01*
X34449Y-180315D02*
Y-179035D01*
X33858Y-179724D02*
X35039D01*
X27756Y-295472D02*
X41142D01*
X27596Y-279232D02*
X41094D01*
X34449Y-287992D02*
Y-286713D01*
X33858Y-287402D02*
X35039D01*
X197933Y-116978D02*
X201673D01*
X199803Y-118848D02*
Y-115108D01*
X266929Y-130905D02*
Y-127362D01*
X265158Y-129134D02*
X268701D01*
X287008Y-121447D02*
X290945D01*
X288976Y-123415D02*
Y-119478D01*
X216535Y-121899D02*
X220472D01*
X218504Y-123868D02*
Y-119931D01*
X112205Y-76624D02*
X116142D01*
X114173Y-78592D02*
Y-74655D01*
X96457Y-95324D02*
X100394D01*
X98425Y-97293D02*
Y-93356D01*
X346137Y-101482D02*
X350075D01*
X348106Y-103451D02*
Y-99514D01*
X445866Y-125836D02*
X449803D01*
X447835Y-127805D02*
Y-123868D01*
X264764Y-112057D02*
X268701D01*
X266732Y-114025D02*
Y-110088D01*
X67913Y-174213D02*
Y-170276D01*
X65945Y-172244D02*
X69882D01*
X68898Y-280512D02*
Y-276575D01*
X66929Y-278543D02*
X70866D01*
X68898Y-226378D02*
Y-222441D01*
X66929Y-224409D02*
X70866D01*
X513976Y-112057D02*
X517913D01*
X515945Y-114025D02*
Y-110088D01*
X528543Y-116781D02*
Y-112844D01*
X526575Y-114813D02*
X530512D01*
X57087Y-159252D02*
Y-155709D01*
X55315Y-157480D02*
X58858D01*
X149705Y-109449D02*
X153445D01*
X151575Y-111319D02*
Y-107579D01*
D20*
X597696Y-224390D02*
Y-221438D01*
X598014D01*
Y-205443D01*
X597696D02*
X598014D01*
X597696D02*
Y-202490D01*
X595353D02*
X597696D01*
X595353D02*
Y-202192D01*
X574240D02*
X595353D01*
X574240Y-202490D02*
Y-202192D01*
X571896Y-202490D02*
X574240D01*
X571896Y-205443D02*
Y-202490D01*
X571579Y-205443D02*
X571896D01*
X571579Y-221438D02*
Y-205443D01*
Y-221438D02*
X571896D01*
Y-224390D02*
Y-221438D01*
Y-224390D02*
X574240D01*
Y-224689D02*
Y-224390D01*
Y-224689D02*
X595353D01*
Y-224390D01*
X597696D01*
X586522Y-282997D02*
Y-280045D01*
X586839D01*
Y-264050D01*
X586522D02*
X586839D01*
X586522D02*
Y-261097D01*
X584179D02*
X586522D01*
X584179D02*
Y-260798D01*
X563065D02*
X584179D01*
X563065Y-261097D02*
Y-260798D01*
X560722Y-261097D02*
X563065D01*
X560722Y-264050D02*
Y-261097D01*
X560405Y-264050D02*
X560722D01*
X560405Y-280045D02*
Y-264050D01*
Y-280045D02*
X560722D01*
Y-282997D02*
Y-280045D01*
Y-282997D02*
X563065D01*
Y-283296D02*
Y-282997D01*
Y-283296D02*
X584179D01*
Y-282997D01*
X586522D01*
D258*
X78543Y-132677D02*
X86811D01*
X78543Y-119291D02*
X86811D01*
X78543Y-132677D02*
Y-119291D01*
X86811Y-132677D02*
Y-119291D01*
X64764Y-115354D02*
Y-112205D01*
X70669Y-115354D02*
Y-112205D01*
X64764D02*
X70669D01*
X64764Y-115354D02*
X70669D01*
X64764Y-111811D02*
Y-108661D01*
X70669Y-111811D02*
Y-108661D01*
X64764D02*
X70669D01*
X64764Y-111811D02*
X70669D01*
X70669Y-119291D02*
Y-116142D01*
X64764Y-119291D02*
Y-116142D01*
Y-119291D02*
X70669D01*
X64764Y-116142D02*
X70669D01*
X661024Y-84252D02*
Y-77953D01*
X664173Y-84252D02*
Y-77953D01*
X661024Y-84252D02*
X664173D01*
X661024Y-77953D02*
X664173D01*
X674016Y-81496D02*
Y-75197D01*
X677165Y-81496D02*
Y-75197D01*
X674016Y-81496D02*
X677165D01*
X674016Y-75197D02*
X677165D01*
X547441Y-272441D02*
X553346D01*
X547441Y-269291D02*
X553346D01*
Y-272441D02*
Y-269291D01*
X547441Y-272441D02*
Y-269291D01*
X606496Y-83661D02*
Y-80118D01*
X613583Y-83661D02*
Y-80118D01*
X606496D02*
X613583D01*
X606496Y-83661D02*
X613583D01*
X602756Y-102953D02*
Y-99409D01*
X609842Y-102953D02*
Y-99409D01*
X602756D02*
X609842D01*
X602756Y-102953D02*
X609842D01*
X579921Y-82480D02*
Y-78937D01*
X587008Y-82480D02*
Y-78937D01*
X579921D02*
X587008D01*
X579921Y-82480D02*
X587008D01*
X572244Y-108071D02*
Y-104527D01*
X579331Y-108071D02*
Y-104527D01*
X572244D02*
X579331D01*
X572244Y-108071D02*
X579331D01*
X233465Y-118307D02*
X236614D01*
X233465Y-112402D02*
X236614D01*
X233465Y-118307D02*
Y-112402D01*
X236614Y-118307D02*
Y-112402D01*
X241929Y-124016D02*
Y-120866D01*
X236024Y-124016D02*
Y-120866D01*
Y-124016D02*
X241929D01*
X236024Y-120866D02*
X241929D01*
X260827Y-106299D02*
Y-103150D01*
X254921Y-106299D02*
Y-103150D01*
Y-106299D02*
X260827D01*
X254921Y-103150D02*
X260827D01*
X258268Y-117520D02*
X261417D01*
X258268Y-123425D02*
X261417D01*
Y-117520D01*
X258268Y-123425D02*
Y-117520D01*
X160630Y-112402D02*
X172441D01*
X160630Y-106496D02*
X172441D01*
Y-112402D02*
Y-106496D01*
X160630Y-112402D02*
Y-106496D01*
X264961Y-121063D02*
Y-116732D01*
X273228Y-121063D02*
Y-116732D01*
X264961D02*
X273228D01*
X264961Y-121063D02*
X273228D01*
X230315Y-112402D02*
X243701D01*
X230315Y-104134D02*
X243701D01*
Y-112402D02*
Y-104134D01*
X230315Y-112402D02*
Y-104134D01*
X669488Y-84646D02*
X673032D01*
X669488Y-77559D02*
X673032D01*
X669488Y-84646D02*
Y-77559D01*
X673032Y-84646D02*
Y-77559D01*
X676575Y-69291D02*
Y-66142D01*
X682480Y-69291D02*
Y-66142D01*
X676575D02*
X682480D01*
X676575Y-69291D02*
X682480D01*
X631102Y-88386D02*
Y-84842D01*
X624016Y-88386D02*
Y-84842D01*
Y-88386D02*
X631102D01*
X624016Y-84842D02*
X631102D01*
X603150Y-91535D02*
Y-87992D01*
X610236Y-91535D02*
Y-87992D01*
X603150D02*
X610236D01*
X603150Y-91535D02*
X610236D01*
X631496Y-101378D02*
Y-97835D01*
X624409Y-101378D02*
Y-97835D01*
Y-101378D02*
X631496D01*
X624409Y-97835D02*
X631496D01*
X603150Y-97047D02*
Y-93504D01*
X610236Y-97047D02*
Y-93504D01*
X603150D02*
X610236D01*
X603150Y-97047D02*
X610236D01*
X592323Y-81496D02*
X595866D01*
X592323Y-88583D02*
X595866D01*
Y-81496D01*
X592323Y-88583D02*
Y-81496D01*
X441142Y-112598D02*
Y-109449D01*
X435236Y-112598D02*
Y-109449D01*
Y-112598D02*
X441142D01*
X435236Y-109449D02*
X441142D01*
X405217Y-112205D02*
Y-109055D01*
X411122Y-112205D02*
Y-109055D01*
X405217D02*
X411122D01*
X405217Y-112205D02*
X411122D01*
X570472Y-89961D02*
Y-86417D01*
X577559Y-89961D02*
Y-86417D01*
X570472D02*
X577559D01*
X570472Y-89961D02*
X577559D01*
X598032Y-99803D02*
Y-96260D01*
X590945Y-99803D02*
Y-96260D01*
Y-99803D02*
X598032D01*
X590945Y-96260D02*
X598032D01*
X570079Y-102165D02*
Y-98622D01*
X577165Y-102165D02*
Y-98622D01*
X570079D02*
X577165D01*
X570079Y-102165D02*
X577165D01*
X241142Y-115748D02*
Y-112598D01*
X247047Y-115748D02*
Y-112598D01*
X241142D02*
X247047D01*
X241142Y-115748D02*
X247047D01*
X241142Y-132283D02*
Y-129134D01*
X247047Y-132283D02*
Y-129134D01*
X241142D02*
X247047D01*
X241142Y-132283D02*
X247047D01*
X258465Y-116929D02*
Y-113779D01*
X252559Y-116929D02*
Y-113779D01*
Y-116929D02*
X258465D01*
X252559Y-113779D02*
X258465D01*
X256890Y-132283D02*
Y-129134D01*
X250984Y-132283D02*
Y-129134D01*
Y-132283D02*
X256890D01*
X250984Y-129134D02*
X256890D01*
X665945Y-84646D02*
X669488D01*
X665945Y-77559D02*
X669488D01*
X665945Y-84646D02*
Y-77559D01*
X669488Y-84646D02*
Y-77559D01*
X683858Y-43110D02*
Y-39567D01*
X676772Y-43110D02*
Y-39567D01*
Y-43110D02*
X683858D01*
X676772Y-39567D02*
X683858D01*
X694685Y-42913D02*
X698228D01*
X694685Y-50000D02*
X698228D01*
Y-42913D01*
X694685Y-50000D02*
Y-42913D01*
X546654Y-267717D02*
Y-264173D01*
X553740Y-267717D02*
Y-264173D01*
X546654D02*
X553740D01*
X546654Y-267717D02*
X553740D01*
X636221Y-215158D02*
X645669D01*
X636221Y-196653D02*
X645669D01*
X636221Y-215158D02*
Y-196653D01*
X645669Y-215158D02*
Y-196653D01*
X613189Y-241732D02*
Y-237795D01*
X620669Y-241732D02*
Y-237795D01*
X613189D02*
X620669D01*
X613189Y-241732D02*
X620669D01*
X615846Y-239764D02*
X618012D01*
X616929Y-240846D02*
Y-238681D01*
X565748Y-218307D02*
X569685D01*
X565748Y-225787D02*
X569685D01*
Y-218307D01*
X565748Y-225787D02*
Y-218307D01*
X567717Y-223130D02*
Y-220965D01*
X566634Y-222047D02*
X568799D01*
X592913Y-232874D02*
X596063D01*
X592913Y-226969D02*
X596063D01*
X592913Y-232874D02*
Y-226969D01*
X596063Y-232874D02*
Y-226969D01*
X610827Y-234449D02*
Y-230118D01*
X602559Y-234449D02*
Y-230118D01*
Y-234449D02*
X610827D01*
X602559Y-230118D02*
X610827D01*
X666142Y-246654D02*
Y-240748D01*
X669291Y-246654D02*
Y-240748D01*
X666142Y-246654D02*
X669291D01*
X666142Y-240748D02*
X669291D01*
X670669Y-240551D02*
X676575D01*
X670669Y-243701D02*
X676575D01*
X670669D02*
Y-240551D01*
X676575Y-243701D02*
Y-240551D01*
X597441Y-233465D02*
X600984D01*
X597441Y-226378D02*
X600984D01*
X597441Y-233465D02*
Y-226378D01*
X600984Y-233465D02*
Y-226378D01*
X645669Y-229331D02*
Y-221850D01*
X641732Y-229331D02*
Y-221850D01*
X645669D01*
X641732Y-229331D02*
X645669D01*
X564370Y-203150D02*
X567913D01*
X564370Y-196063D02*
X567913D01*
X564370Y-203150D02*
Y-196063D01*
X567913Y-203150D02*
Y-196063D01*
X547835Y-202559D02*
Y-198228D01*
X556102Y-202559D02*
Y-198228D01*
X547835D02*
X556102D01*
X547835Y-202559D02*
X556102D01*
X552559Y-209252D02*
X556890D01*
X552559Y-217520D02*
X556890D01*
Y-209252D01*
X552559Y-217520D02*
Y-209252D01*
X560039Y-207087D02*
Y-203937D01*
X565945Y-207087D02*
Y-203937D01*
X560039D02*
X565945D01*
X560039Y-207087D02*
X565945D01*
X560039Y-210630D02*
Y-207480D01*
X565945Y-210630D02*
Y-207480D01*
X560039D02*
X565945D01*
X560039Y-210630D02*
X565945D01*
X549016Y-107480D02*
X554921D01*
X549016Y-110630D02*
X554921D01*
X549016D02*
Y-107480D01*
X554921Y-110630D02*
Y-107480D01*
X561221Y-111024D02*
X567126D01*
X561221Y-107874D02*
X567126D01*
Y-111024D02*
Y-107874D01*
X561221Y-111024D02*
Y-107874D01*
X547441Y-276378D02*
Y-273228D01*
X553346Y-276378D02*
Y-273228D01*
X547441D02*
X553346D01*
X547441Y-276378D02*
X553346D01*
X605905Y-291535D02*
X609842D01*
X605905Y-299016D02*
X609842D01*
Y-291535D01*
X605905Y-299016D02*
Y-291535D01*
X607874Y-296358D02*
Y-294193D01*
X606791Y-295276D02*
X608957D01*
X556890Y-288583D02*
Y-284646D01*
X564370Y-288583D02*
Y-284646D01*
X556890D02*
X564370D01*
X556890Y-288583D02*
X564370D01*
X559547Y-286614D02*
X561713D01*
X560630Y-287697D02*
Y-285531D01*
X579331Y-291929D02*
Y-287598D01*
X587598Y-291929D02*
Y-287598D01*
X579331D02*
X587598D01*
X579331Y-291929D02*
X587598D01*
X630118Y-274016D02*
Y-264567D01*
X648622Y-274016D02*
Y-264567D01*
X630118D02*
X648622D01*
X630118Y-274016D02*
X648622D01*
X592520Y-286811D02*
X595669D01*
X592520Y-280906D02*
X595669D01*
X592520Y-286811D02*
Y-280906D01*
X595669Y-286811D02*
Y-280906D01*
X545965Y-287205D02*
Y-282874D01*
X554232Y-287205D02*
Y-282874D01*
X545965D02*
X554232D01*
X545965Y-287205D02*
X554232D01*
X579921D02*
Y-283661D01*
X587008Y-287205D02*
Y-283661D01*
X579921D02*
X587008D01*
X579921Y-287205D02*
X587008D01*
X551181Y-263189D02*
X554724D01*
X551181Y-256102D02*
X554724D01*
X551181Y-263189D02*
Y-256102D01*
X554724Y-263189D02*
Y-256102D01*
X660827Y-281102D02*
X668307D01*
X660827Y-285039D02*
X668307D01*
X660827D02*
Y-281102D01*
X668307Y-285039D02*
Y-281102D01*
X679331Y-303543D02*
X685236D01*
X679331Y-300394D02*
X685236D01*
Y-303543D02*
Y-300394D01*
X679331Y-303543D02*
Y-300394D01*
Y-307874D02*
X685236D01*
X679331Y-304724D02*
X685236D01*
Y-307874D02*
Y-304724D01*
X679331Y-307874D02*
Y-304724D01*
X572047Y-154528D02*
X581496D01*
X572047Y-136024D02*
X581496D01*
X572047Y-154528D02*
Y-136024D01*
X581496Y-154528D02*
Y-136024D01*
X530512Y-143307D02*
X537992D01*
X530512Y-139370D02*
X537992D01*
Y-143307D02*
Y-139370D01*
X530512Y-143307D02*
Y-139370D01*
X494291Y-139370D02*
X501772D01*
X494291Y-143307D02*
X501772D01*
X494291D02*
Y-139370D01*
X501772Y-143307D02*
Y-139370D01*
X494291Y-135433D02*
X501772D01*
X494291Y-139370D02*
X501772D01*
X494291D02*
Y-135433D01*
X501772Y-139370D02*
Y-135433D01*
X503150Y-108465D02*
X506299D01*
X503150Y-114370D02*
X506299D01*
Y-108465D01*
X503150Y-114370D02*
Y-108465D01*
X507087D02*
X510236D01*
X507087Y-114370D02*
X510236D01*
Y-108465D01*
X507087Y-114370D02*
Y-108465D01*
X472047Y-125000D02*
X475197D01*
X472047Y-119095D02*
X475197D01*
X472047Y-125000D02*
Y-119095D01*
X475197Y-125000D02*
Y-119095D01*
X494685Y-110630D02*
Y-107480D01*
X488779Y-110630D02*
Y-107480D01*
Y-110630D02*
X494685D01*
X488779Y-107480D02*
X494685D01*
X475000Y-118504D02*
Y-115354D01*
X469095Y-118504D02*
Y-115354D01*
Y-118504D02*
X475000D01*
X469095Y-115354D02*
X475000D01*
X487992Y-110630D02*
Y-107480D01*
X482087Y-110630D02*
Y-107480D01*
Y-110630D02*
X487992D01*
X482087Y-107480D02*
X487992D01*
X507283Y-121260D02*
Y-118110D01*
X501378Y-121260D02*
Y-118110D01*
Y-121260D02*
X507283D01*
X501378Y-118110D02*
X507283D01*
X471457Y-136221D02*
Y-133071D01*
X477362Y-136221D02*
Y-133071D01*
X471457D02*
X477362D01*
X471457Y-136221D02*
X477362D01*
X504724Y-129331D02*
Y-121850D01*
X500787Y-129331D02*
Y-121850D01*
X504724D01*
X500787Y-129331D02*
X504724D01*
X500197Y-131496D02*
X507677D01*
X500197Y-135433D02*
X507677D01*
X500197D02*
Y-131496D01*
X507677Y-135433D02*
Y-131496D01*
X475394Y-110630D02*
X481299D01*
X475394Y-107480D02*
X481299D01*
Y-110630D02*
Y-107480D01*
X475394Y-110630D02*
Y-107480D01*
X51772Y-46457D02*
Y-33071D01*
X60039Y-46457D02*
Y-33071D01*
X51772Y-46457D02*
X60039D01*
X51772Y-33071D02*
X60039D01*
X107283Y-47244D02*
Y-33858D01*
X115551Y-47244D02*
Y-33858D01*
X107283Y-47244D02*
X115551D01*
X107283Y-33858D02*
X115551D01*
X661417Y-43110D02*
X674803D01*
X661417Y-51378D02*
X674803D01*
X661417D02*
Y-43110D01*
X674803Y-51378D02*
Y-43110D01*
X598819Y-49016D02*
X612205D01*
X598819Y-40748D02*
X612205D01*
Y-49016D02*
Y-40748D01*
X598819Y-49016D02*
Y-40748D01*
X421850Y-185433D02*
X427756D01*
X421850Y-182283D02*
X427756D01*
Y-185433D02*
Y-182283D01*
X421850Y-185433D02*
Y-182283D01*
X138583Y-132480D02*
Y-126575D01*
X141732Y-132480D02*
Y-126575D01*
X138583Y-132480D02*
X141732D01*
X138583Y-126575D02*
X141732D01*
X134862Y-125965D02*
Y-114193D01*
X188130D01*
Y-125965D02*
Y-114193D01*
X134862Y-125965D02*
X188130D01*
X354670Y-118307D02*
X375930D01*
X354670Y-106890D02*
X375930D01*
Y-118307D02*
Y-106890D01*
X354670Y-118307D02*
Y-106890D01*
Y-141929D02*
Y-130512D01*
X375930Y-141929D02*
Y-130512D01*
X354670D02*
X375930D01*
X354670Y-141929D02*
X375930D01*
X563976Y-113779D02*
X572244D01*
X563976Y-127165D02*
X572244D01*
Y-113779D01*
X563976Y-127165D02*
Y-113779D01*
X605905Y-173425D02*
Y-162008D01*
X584646Y-173425D02*
Y-162008D01*
Y-173425D02*
X605905D01*
X584646Y-162008D02*
X605905D01*
X354670Y-130512D02*
Y-119095D01*
X375930Y-130512D02*
Y-119095D01*
X354670D02*
X375930D01*
X354670Y-130512D02*
X375930D01*
X548307Y-354528D02*
X630276D01*
Y-305551D01*
X548307D02*
X630276D01*
X548307Y-354528D02*
Y-305551D01*
X-54527Y-331505D02*
X6260D01*
Y-302057D01*
X-54527D02*
X6260D01*
X-54527Y-331505D02*
Y-302057D01*
X-54528Y-278354D02*
X6260D01*
Y-248905D01*
X-54528D02*
X6260D01*
X-54528Y-278354D02*
Y-248905D01*
Y-225205D02*
X6260D01*
Y-195756D01*
X-54528D02*
X6260D01*
X-54528Y-225205D02*
Y-195756D01*
X-54527Y-172057D02*
X6260D01*
Y-142608D01*
X-54527D02*
X6260D01*
X-54527Y-172057D02*
Y-142608D01*
X66929Y-217717D02*
X84646D01*
X66929D02*
Y-207480D01*
X84646D01*
Y-217717D02*
Y-207480D01*
X65945Y-164567D02*
X83661D01*
X65945D02*
Y-154331D01*
X83661D01*
Y-164567D02*
Y-154331D01*
X44291Y-7283D02*
X50197D01*
X44291Y3347D02*
X50197D01*
X44291Y-7283D02*
Y3347D01*
X50197Y-7283D02*
Y3347D01*
X37402Y-7283D02*
X43307D01*
X37402Y3347D02*
X43307D01*
X37402Y-7283D02*
Y3347D01*
X43307Y-7283D02*
Y3347D01*
X30512Y-7283D02*
X36417D01*
X30512Y3347D02*
X36417D01*
X30512Y-7283D02*
Y3347D01*
X36417Y-7283D02*
Y3347D01*
X23622Y-7283D02*
X29528D01*
X23622Y3347D02*
X29528D01*
X23622Y-7283D02*
Y3347D01*
X29528Y-7283D02*
Y3347D01*
X91240Y-138091D02*
Y-113878D01*
X115453Y-138091D02*
Y-113878D01*
X91240D02*
X115453D01*
X91240Y-138091D02*
X115453D01*
X73819Y-138779D02*
X85630D01*
X73819Y-132874D02*
X85630D01*
Y-138779D02*
Y-132874D01*
X73819Y-138779D02*
Y-132874D01*
X66929Y-269882D02*
X84646D01*
X66929D02*
Y-259646D01*
X84646D01*
Y-269882D02*
Y-259646D01*
X35827Y-271063D02*
Y-254528D01*
X50787D01*
X35827Y-271063D02*
X50787D01*
Y-254528D01*
X35827Y-165748D02*
Y-149213D01*
X50787D01*
X35827Y-165748D02*
X50787D01*
Y-149213D01*
X71850Y-338583D02*
Y-326772D01*
X77756Y-338583D02*
Y-326772D01*
X71850Y-338583D02*
X77756D01*
X71850Y-326772D02*
X77756D01*
X79724Y-338583D02*
Y-326772D01*
X85630Y-338583D02*
Y-326772D01*
X79724Y-338583D02*
X85630D01*
X79724Y-326772D02*
X85630D01*
X65945Y-324016D02*
X83661D01*
X65945D02*
Y-313779D01*
X83661D01*
Y-324016D02*
Y-313779D01*
X35827Y-325197D02*
Y-308661D01*
X50787D01*
X35827Y-325197D02*
X50787D01*
Y-308661D01*
X35827Y-218898D02*
Y-202362D01*
X50787D01*
X35827Y-218898D02*
X50787D01*
Y-202362D01*
X62008Y-319685D02*
Y-314173D01*
X51772Y-319685D02*
Y-314173D01*
Y-319685D02*
X62008D01*
X51772Y-314173D02*
X62008D01*
X63189Y-213386D02*
Y-207874D01*
X52953Y-213386D02*
Y-207874D01*
Y-213386D02*
X63189D01*
X52953Y-207874D02*
X63189D01*
Y-265551D02*
Y-260039D01*
X52953Y-265551D02*
Y-260039D01*
Y-265551D02*
X63189D01*
X52953Y-260039D02*
X63189D01*
X72835Y-230315D02*
Y-218504D01*
X78740Y-230315D02*
Y-218504D01*
X72835Y-230315D02*
X78740D01*
X72835Y-218504D02*
X78740D01*
X79724Y-230315D02*
Y-218504D01*
X85630Y-230315D02*
Y-218504D01*
X79724Y-230315D02*
X85630D01*
X79724Y-218504D02*
X85630D01*
X80709Y-284449D02*
Y-272638D01*
X86614Y-284449D02*
Y-272638D01*
X80709Y-284449D02*
X86614D01*
X80709Y-272638D02*
X86614D01*
X72835Y-284449D02*
Y-272638D01*
X78740Y-284449D02*
Y-272638D01*
X72835Y-284449D02*
X78740D01*
X72835Y-272638D02*
X78740D01*
X71850Y-178150D02*
Y-166339D01*
X77756Y-178150D02*
Y-166339D01*
X71850Y-178150D02*
X77756D01*
X71850Y-166339D02*
X77756D01*
X79724Y-178150D02*
Y-166339D01*
X85630Y-178150D02*
Y-166339D01*
X79724Y-178150D02*
X85630D01*
X79724Y-166339D02*
X85630D01*
X462795Y-140009D02*
Y-135285D01*
X454528Y-140009D02*
Y-135285D01*
Y-140009D02*
X462795D01*
X454528Y-135285D02*
X462795D01*
X662205Y-12008D02*
X675591D01*
X662205Y-20276D02*
X675591D01*
X662205D02*
Y-12008D01*
X675591Y-20276D02*
Y-12008D01*
X606074Y-18151D02*
X619459D01*
X606074Y-9883D02*
X619459D01*
Y-18151D02*
Y-9883D01*
X606074Y-18151D02*
Y-9883D01*
X63779Y-339370D02*
Y-325984D01*
X72047Y-339370D02*
Y-325984D01*
X63779Y-339370D02*
X72047D01*
X63779Y-325984D02*
X72047D01*
X196850Y-122096D02*
Y-111860D01*
X202756Y-122096D02*
Y-111860D01*
X196850Y-122096D02*
X202756D01*
X196850Y-111860D02*
X202756D01*
X262795Y-131299D02*
X271063D01*
X262795Y-126969D02*
X271063D01*
Y-131299D02*
Y-126969D01*
X262795Y-131299D02*
Y-126969D01*
X274213Y-132273D02*
Y-110620D01*
X303740Y-132273D02*
Y-110620D01*
X274213D02*
X303740D01*
X274213Y-132273D02*
X303740D01*
X205118Y-132135D02*
Y-111663D01*
X231890Y-132135D02*
Y-111663D01*
X205118D02*
X231890D01*
X205118Y-132135D02*
X231890D01*
X118307Y-83316D02*
Y-69931D01*
X110039Y-83316D02*
Y-69931D01*
X118307D01*
X110039Y-83316D02*
X118307D01*
X102559Y-102017D02*
Y-88631D01*
X94291Y-102017D02*
Y-88631D01*
X102559D01*
X94291Y-102017D02*
X102559D01*
X343972Y-108175D02*
Y-94789D01*
X352240Y-108175D02*
Y-94789D01*
X343972Y-108175D02*
X352240D01*
X343972Y-94789D02*
X352240D01*
X443701Y-132529D02*
Y-119143D01*
X451968Y-132529D02*
Y-119143D01*
X443701Y-132529D02*
X451968D01*
X443701Y-119143D02*
X451968D01*
X260039Y-116191D02*
Y-107923D01*
X273425Y-116191D02*
Y-107923D01*
X260039D02*
X273425D01*
X260039Y-116191D02*
X273425D01*
X63779Y-165551D02*
X72047D01*
X63779Y-178937D02*
X72047D01*
Y-165551D01*
X63779Y-178937D02*
Y-165551D01*
X64764Y-271850D02*
X73032D01*
X64764Y-285236D02*
X73032D01*
Y-271850D01*
X64764Y-285236D02*
Y-271850D01*
X64764Y-217717D02*
X73032D01*
X64764Y-231102D02*
X73032D01*
Y-217717D01*
X64764Y-231102D02*
Y-217717D01*
X522638Y-116191D02*
Y-107923D01*
X509252Y-116191D02*
Y-107923D01*
Y-116191D02*
X522638D01*
X509252Y-107923D02*
X522638D01*
X524409Y-108120D02*
X532677D01*
X524409Y-121505D02*
X532677D01*
Y-108120D01*
X524409Y-121505D02*
Y-108120D01*
X51968Y-154724D02*
X62205D01*
X51968Y-160236D02*
X62205D01*
X51968D02*
Y-154724D01*
X62205Y-160236D02*
Y-154724D01*
X145669Y-112402D02*
Y-106496D01*
X157480Y-112402D02*
Y-106496D01*
X145669D02*
X157480D01*
X145669Y-112402D02*
X157480D01*
D259*
X536556Y-333706D02*
Y-329769D01*
X534588Y-331738D02*
X538525D01*
X529469Y-335675D02*
X543643D01*
X529469Y-327801D02*
X543643D01*
Y-335675D02*
Y-327801D01*
X529469Y-335675D02*
Y-327801D01*
X536162Y-349848D02*
Y-345911D01*
X534194Y-347880D02*
X538131D01*
X529076Y-351817D02*
X543249D01*
X529076Y-343943D02*
X543249D01*
Y-351817D02*
Y-343943D01*
X529076Y-351817D02*
Y-343943D01*
X653150Y-342520D02*
X657087D01*
X655118Y-344488D02*
Y-340551D01*
X651181Y-349606D02*
Y-335433D01*
X659055Y-349606D02*
Y-335433D01*
X651181Y-349606D02*
X659055D01*
X651181Y-335433D02*
X659055D01*
X512540Y-337053D02*
Y-326423D01*
X526714Y-337053D02*
Y-326423D01*
X512540D02*
X526714D01*
X512540Y-337053D02*
X526714D01*
X517659Y-331738D02*
X521595D01*
X519627Y-333706D02*
Y-329769D01*
X512442Y-353195D02*
Y-342565D01*
X526615Y-353195D02*
Y-342565D01*
X512442D02*
X526615D01*
X512442Y-353195D02*
X526615D01*
X517560Y-347880D02*
X521497D01*
X519529Y-349848D02*
Y-345911D01*
X631693Y-317717D02*
X642323D01*
X631693Y-331890D02*
X642323D01*
Y-317717D01*
X631693Y-331890D02*
Y-317717D01*
X637008Y-326772D02*
Y-322835D01*
X635039Y-324803D02*
X638976D01*
X650394Y-317815D02*
X661024D01*
X650394Y-331988D02*
X661024D01*
Y-317815D01*
X650394Y-331988D02*
Y-317815D01*
X655709Y-326870D02*
Y-322933D01*
X653740Y-324902D02*
X657677D01*
X635039Y-342913D02*
X638976D01*
X637008Y-344882D02*
Y-340945D01*
X633071Y-350000D02*
Y-335827D01*
X640945Y-350000D02*
Y-335827D01*
X633071Y-350000D02*
X640945D01*
X633071Y-335827D02*
X640945D01*
X575591Y-120866D02*
X579528D01*
X577559Y-122835D02*
Y-118898D01*
X581496Y-127953D02*
Y-113779D01*
X573622Y-127953D02*
Y-113779D01*
X581496D01*
X573622Y-127953D02*
X581496D01*
X27596Y-187555D02*
Y-171555D01*
X41142Y-187795D02*
Y-171653D01*
X27596Y-295232D02*
Y-279232D01*
X41142Y-295472D02*
Y-279331D01*
X133071Y-348425D02*
Y-346063D01*
X131890Y-347244D02*
X134252D01*
X129528Y-349016D02*
X136614D01*
X129528Y-345472D02*
X136614D01*
Y-349016D02*
Y-345472D01*
X129528Y-349016D02*
Y-345472D01*
X599606Y-162008D02*
Y-156890D01*
X590158Y-162008D02*
Y-156890D01*
Y-162008D02*
X599606D01*
X590158Y-156890D02*
X599606D01*
X593012Y-159449D02*
X596752D01*
X594882Y-161319D02*
Y-157579D01*
X355512Y-100394D02*
X359449D01*
X357480Y-102362D02*
Y-98425D01*
X361417Y-107480D02*
Y-93307D01*
X353543Y-107480D02*
Y-93307D01*
X361417D01*
X353543Y-107480D02*
X361417D01*
X271472Y-384340D02*
X275410D01*
X271472Y-376860D02*
X275410D01*
Y-384340D02*
Y-376860D01*
X271472Y-384340D02*
Y-376860D01*
X273441Y-381781D02*
Y-379419D01*
X272260Y-380600D02*
X274622D01*
X205260D02*
X207622D01*
X206441Y-381781D02*
Y-379419D01*
X204472Y-384340D02*
Y-376860D01*
X208410Y-384340D02*
Y-376860D01*
X204472D02*
X208410D01*
X204472Y-384340D02*
X208410D01*
X208472D02*
X212409D01*
X208472Y-376860D02*
X212409D01*
Y-384340D02*
Y-376860D01*
X208472Y-384340D02*
Y-376860D01*
X210441Y-381781D02*
Y-379419D01*
X209260Y-380600D02*
X211622D01*
X217160D02*
X219522D01*
X218341Y-381781D02*
Y-379419D01*
X216372Y-384340D02*
Y-376860D01*
X220309Y-384340D02*
Y-376860D01*
X216372D02*
X220309D01*
X216372Y-384340D02*
X220309D01*
X220672D02*
X224609D01*
X220672Y-376860D02*
X224609D01*
Y-384340D02*
Y-376860D01*
X220672Y-384340D02*
Y-376860D01*
X222641Y-381781D02*
Y-379419D01*
X221460Y-380600D02*
X223822D01*
X235972Y-384340D02*
X239910D01*
X235972Y-376860D02*
X239910D01*
Y-384340D02*
Y-376860D01*
X235972Y-384340D02*
Y-376860D01*
X237941Y-381781D02*
Y-379419D01*
X236760Y-380600D02*
X239122D01*
X239972Y-384340D02*
X243910D01*
X239972Y-376860D02*
X243910D01*
Y-384340D02*
Y-376860D01*
X239972Y-384340D02*
Y-376860D01*
X241941Y-381781D02*
Y-379419D01*
X240760Y-380600D02*
X243122D01*
X251472Y-384340D02*
X255410D01*
X251472Y-376860D02*
X255410D01*
Y-384340D02*
Y-376860D01*
X251472Y-384340D02*
Y-376860D01*
X253441Y-381781D02*
Y-379419D01*
X252260Y-380600D02*
X254622D01*
X255760D02*
X258122D01*
X256941Y-381781D02*
Y-379419D01*
X254972Y-384340D02*
Y-376860D01*
X258910Y-384340D02*
Y-376860D01*
X254972D02*
X258910D01*
X254972Y-384340D02*
X258910D01*
X267472D02*
X271410D01*
X267472Y-376860D02*
X271410D01*
Y-384340D02*
Y-376860D01*
X267472Y-384340D02*
Y-376860D01*
X269441Y-381781D02*
Y-379419D01*
X268260Y-380600D02*
X270622D01*
X113425Y-265502D02*
Y-261761D01*
X111555Y-263632D02*
X115295D01*
X108701Y-261072D02*
X118150D01*
X108701Y-266191D02*
X118150D01*
X108701D02*
Y-261072D01*
X118150Y-266191D02*
Y-261072D01*
X133071Y-344094D02*
Y-341732D01*
X131890Y-342913D02*
X134252D01*
X129528Y-344685D02*
X136614D01*
X129528Y-341142D02*
X136614D01*
Y-344685D02*
Y-341142D01*
X129528Y-344685D02*
Y-341142D01*
M02*
